# TIMECARD (Time Appliance Project (Time Card)) — schematic netlist excerpt (pin names and nets, part order shuffled) for the footprints in the layout excerpt that follows; sources: Cadence DE-HDL packaged netlist, KiCad conversion of R4006-B0001-02_R01.brd

R4  RESISTOR  10KOHM 1%  pkg SMC_0402R_H016  page 27 : \1\ = XP12R0V_IN ; \2\ = XP12R0V_A_EN
R86  RESISTOR  0OHM -  pkg SMC_0402R_H016  page 21 : \1\ = FPGA_OUT_MAC_PPS_IN0N ; \2\ = R_MAC_PPS_IN0N

(kicad_pcb
	(version 20260206)
	(generator "pcbnew")
	(generator_version "10.0")
	(general
		(thickness 1.6)
		(legacy_teardrops no)
	)
	(paper "A4")
	(title_block
		(title "timecard-production-celestica-r4006 — R4006-B0001-02_R01.brd")
		(comment 1 "Time Appliance Project (Time Card) / footprints 393-394 of 1113")
	)
	(layers
		(0 "F.Cu" signal "TOP")
		(4 "In1.Cu" signal "L02_GND1")
		(6 "In2.Cu" signal "L03_SIG1")
		(8 "In3.Cu" signal "L04_GND2")
		(10 "In4.Cu" signal "L05_VCC1")
		(12 "In5.Cu" signal "L06_VCC2")
		(14 "In6.Cu" signal "L07_GND3")
		(16 "In7.Cu" signal "L08_SIG2")
		(18 "In8.Cu" signal "L09_GND4")
		(2 "B.Cu" signal "BOTTOM")
		(9 "F.Adhes" user "F.Adhesive")
		(11 "B.Adhes" user "B.Adhesive")
		(13 "F.Paste" user "Package Geometry/Pastemask Top")
		(15 "B.Paste" user "Package Geometry/Pastemask Bottom")
		(5 "F.SilkS" user "Ref Des/Silkscreen Top")
		(7 "B.SilkS" user "Ref Des/Silkscreen Bottom")
		(1 "F.Mask" user "Board Geometry/Soldermask Top")
		(3 "B.Mask" user "Board Geometry/Soldermask Bottom")
		(17 "Dwgs.User" user "User.Drawings")
		(19 "Cmts.User" user "User.Comments")
		(21 "Eco1.User" user "User.Eco1")
		(23 "Eco2.User" user "User.Eco2")
		(25 "Edge.Cuts" user "Board Geometry/Outline")
		(27 "Margin" user)
		(31 "F.CrtYd" user "Package Geometry/Place Bound Top")
		(29 "B.CrtYd" user "Package Geometry/Place Bound Bottom")
		(35 "F.Fab" user "Ref Des/Assembly Top")
		(33 "B.Fab" user "Ref Des/Assembly Bottom")
	)
	(footprint ""
		(layer "F.Cu")
		(at 145.8214 -88.0618 180)
		(property "Reference" "R4"
			(at 0.2794 -7.71017 0)
			(unlocked yes)
			(layer "F.SilkS")
			(effects
				(font
					(size 0.7874 0.5842)
					(thickness 0.1524)
				)
			)
		)
		(property "Value" "VAL*"
			(at 0.02032 2.13233 180)
			(unlocked yes)
			(layer "F.Fab")
			(hide yes)
			(effects
				(font
					(size 0.7874 0.5842)
					(thickness 0.1524)
				)
			)
		)
		(property "Device Type" "RESISTOR-G155-11002-01,10KOHM,A"
			(at 0.008382 1.210564 180)
			(unlocked yes)
			(layer "F.Fab")
			(hide yes)
			(effects
				(font
					(size 0.7874 0.5842)
					(thickness 0.1524)
				)
			)
		)
		(property "User Part Number" "PARTNUM*"
			(at 0.02032 4.024884 180)
			(unlocked yes)
			(layer "Cmts.User")
			(hide yes)
			(effects
				(font
					(size 0.7874 0.5842)
					(thickness 0.1524)
				)
			)
		)
		(property "Tolerance" "TOL*"
			(at 0.044704 3.05435 180)
			(unlocked yes)
			(layer "Cmts.User")
			(hide yes)
			(effects
				(font
					(size 0.7874 0.5842)
					(thickness 0.1524)
				)
			)
		)
		(duplicate_pad_numbers_are_jumpers no)
		(fp_line
			(start 1.143 0.5588)
			(end 1.143 -0.5588)
			(stroke
				(width 0.1)
				(type default)
			)
			(layer "F.SilkS")
		)
		(fp_line
			(start 1.143 -0.5588)
			(end -1.143 -0.5588)
			(stroke
				(width 0.1)
				(type default)
			)
			(layer "F.SilkS")
		)
		(fp_line
			(start -1.143 0.5588)
			(end 1.143 0.5588)
			(stroke
				(width 0.1)
				(type default)
			)
			(layer "F.SilkS")
		)
		(fp_line
			(start -1.143 -0.5588)
			(end -1.143 0.5588)
			(stroke
				(width 0.1)
				(type default)
			)
			(layer "F.SilkS")
		)
		(fp_rect
			(start 1.143 0.5588)
			(end -1.143 -0.5588)
			(stroke
				(width 0)
				(type default)
			)
			(fill no)
			(layer "F.CrtYd")
		)
		(fp_line
			(start 0.508 0.3048)
			(end 0.508 -0.3048)
			(stroke
				(width 0.1)
				(type default)
			)
			(layer "F.Fab")
		)
		(fp_line
			(start 0.508 -0.3048)
			(end -0.508 -0.3048)
			(stroke
				(width 0.1)
				(type default)
			)
			(layer "F.Fab")
		)
		(fp_line
			(start -0.508 0.3048)
			(end 0.508 0.3048)
			(stroke
				(width 0.1)
				(type default)
			)
			(layer "F.Fab")
		)
		(fp_line
			(start -0.508 -0.3048)
			(end -0.508 0.3048)
			(stroke
				(width 0.1)
				(type default)
			)
			(layer "F.Fab")
		)
		(pad "1" smd rect
			(at -0.5334 0 180)
			(size 0.7112 0.6096)
			(layers "F.Cu" "F.Mask" "F.Paste")
			(net "XP12R0V_IN")
		)
		(pad "2" smd rect
			(at 0.5334 0 180)
			(size 0.7112 0.6096)
			(layers "F.Cu" "F.Mask" "F.Paste")
			(net "XP12R0V_A_EN")
		)
		(zone
			(layer "F.Cu")
			(hatch none 0.5)
			(connect_pads
				(clearance 0)
			)
			(min_thickness 0.25)
			(keepout
				(tracks allowed)
				(vias not_allowed)
				(pads allowed)
				(copperpour not_allowed)
				(footprints allowed)
			)
			(placement
				(enabled no)
				(sheetname "")
			)
			(fill
				(thermal_gap 0.5)
				(thermal_bridge_width 0.5)
				(island_removal_mode 0)
			)
			(polygon
				(pts
					(xy 145.7452 -88.3666) (xy 145.7452 -87.757) (xy 145.8976 -87.757) (xy 145.8976 -88.3666)
				)
			)
		)
	)
	(footprint ""
		(layer "F.Cu")
		(at 81.0006 -49.911 180)
		(property "Reference" "R86"
			(at 1.016 -14.64437 0)
			(unlocked yes)
			(layer "F.SilkS")
			(effects
				(font
					(size 0.7874 0.5842)
					(thickness 0.1524)
				)
			)
		)
		(property "Value" "VAL*"
			(at 0.02032 2.13233 180)
			(unlocked yes)
			(layer "F.Fab")
			(hide yes)
			(effects
				(font
					(size 0.7874 0.5842)
					(thickness 0.1524)
				)
			)
		)
		(property "Tolerance" "TOL*"
			(at 0.044704 3.05435 180)
			(unlocked yes)
			(layer "Cmts.User")
			(hide yes)
			(effects
				(font
					(size 0.7874 0.5842)
					(thickness 0.1524)
				)
			)
		)
		(property "User Part Number" "PARTNUM*"
			(at 0.02032 4.024884 180)
			(unlocked yes)
			(layer "Cmts.User")
			(hide yes)
			(effects
				(font
					(size 0.7874 0.5842)
					(thickness 0.1524)
				)
			)
		)
		(property "Device Type" "RESISTOR-G155-100R0-J0,0OHM,-"
			(at 0.008382 1.210564 180)
			(unlocked yes)
			(layer "F.Fab")
			(hide yes)
			(effects
				(font
					(size 0.7874 0.5842)
					(thickness 0.1524)
				)
			)
		)
		(duplicate_pad_numbers_are_jumpers no)
		(fp_line
			(start 1.143 0.5588)
			(end 1.143 -0.5588)
			(stroke
				(width 0.1)
				(type default)
			)
			(layer "F.SilkS")
		)
		(fp_line
			(start 1.143 -0.5588)
			(end -1.143 -0.5588)
			(stroke
				(width 0.1)
				(type default)
			)
			(layer "F.SilkS")
		)
		(fp_line
			(start -1.143 0.5588)
			(end 1.143 0.5588)
			(stroke
				(width 0.1)
				(type default)
			)
			(layer "F.SilkS")
		)
		(fp_line
			(start -1.143 -0.5588)
			(end -1.143 0.5588)
			(stroke
				(width 0.1)
				(type default)
			)
			(layer "F.SilkS")
		)
		(fp_rect
			(start 1.143 -0.5588)
			(end -1.143 0.5588)
			(stroke
				(width 0)
				(type default)
			)
			(fill no)
			(layer "F.CrtYd")
		)
		(fp_line
			(start 0.508 0.3048)
			(end 0.508 -0.3048)
			(stroke
				(width 0.1)
				(type default)
			)
			(layer "F.Fab")
		)
		(fp_line
			(start 0.508 -0.3048)
			(end -0.508 -0.3048)
			(stroke
				(width 0.1)
				(type default)
			)
			(layer "F.Fab")
		)
		(fp_line
			(start -0.508 0.3048)
			(end 0.508 0.3048)
			(stroke
				(width 0.1)
				(type default)
			)
			(layer "F.Fab")
		)
		(fp_line
			(start -0.508 -0.3048)
			(end -0.508 0.3048)
			(stroke
				(width 0.1)
				(type default)
			)
			(layer "F.Fab")
		)
		(pad "1" smd rect
			(at -0.5334 0 180)
			(size 0.7112 0.6096)
			(layers "F.Cu" "F.Mask" "F.Paste")
			(net "FPGA_OUT_MAC_PPS_IN0N")
		)
		(pad "2" smd rect
			(at 0.5334 0 180)
			(size 0.7112 0.6096)
			(layers "F.Cu" "F.Mask" "F.Paste")
			(net "R_MAC_PPS_IN0N")
		)
		(zone
			(layer "F.Cu")
			(hatch none 0.5)
			(connect_pads
				(clearance 0)
			)
			(min_thickness 0.25)
			(keepout
				(tracks allowed)
				(vias not_allowed)
				(pads allowed)
				(copperpour not_allowed)
				(footprints allowed)
			)
			(placement
				(enabled no)
				(sheetname "")
			)
			(fill
				(thermal_gap 0.5)
				(thermal_bridge_width 0.5)
				(island_removal_mode 0)
			)
			(polygon
				(pts
					(xy 80.9244 -49.6062) (xy 81.0768 -49.6062) (xy 81.0768 -50.2158) (xy 80.9244 -50.2158)
				)
			)
		)
	)
)
